# T6G (Grand Teton) — schematic netlist excerpt (pin names and nets, part order shuffled) for the footprints in the layout excerpt that follows; sources: Cadence DE-HDL packaged netlist, KiCad conversion of 04192023_DAF0TMB3IC0_F0TG_MB_C_brd_V02_OCP.brd

PU12  RAA229620GNPHA0  RAA229620GNP#HA0 IC  pkg QFN48_TH_0-4_6X6XH  page 200
  PWM0  = PVDDIO_P0_PWM1
  PWM1  = PVDDIO_P0_PWM2
  PWM2  = PVDDIO_P0_PWM3
  PWM3  = PVDDIO_P0_PWM4
  PWM4  = NC_PVDDCR_CPU1_P0_PWM8
  PWM5  = NC_PVDDCR_CPU1_P0_PWM7
  PWM6  = PVDDCR_CPU1_P0_PWM6
  PWM7  = PVDDCR_CPU1_P0_PWM5
  PWM8  = PVDDCR_CPU1_P0_PWM4
  PWM9  = PVDDCR_CPU1_P0_PWM3
  PWM10  = PVDDCR_CPU1_P0_PWM2
  PWM11  = PVDDCR_CPU1_P0_PWM1
  PMSDA  = SMB_DIO_PVDDCR_CPU1_P0_R
  PMSCL  = SMB_CLK_PVDDCR_CPU1_P0_R
  NPMALERT  = PVDDCR_CPU1_P0_SMB_ALERT_R
  PG0  = PWRGD_PVDDCR_CPU1_P0_R
  EN0  = PVDDCR_CPU1_P0_EN_R
  RESET_L  = PVDDCR_CPU1_P0_RESET_N_R
  VDDIO  = PVDD18_S5_P0
  PG1  = PWRGD_PVDDIO_P0_R
  SVD  = SVID_PVDDCR_CPU1_P0_SVD_R1
  SVC  = SVID_PVDDCR_CPU1_P0_SVC_R1
  SVTO  = SVID_PVDDCR_CPU1_P0_SVTO_R
  SVTI  = SVID_PVDDCR_CPU1_P0_SVTI_R
  VSEN0  = VSENSE_PVDDCR_CPU1_P0_VSEN0
  RGND0  = VSENSE_VSS_SENSE_C_P0
  CS11  = PVDDCR_CPU1_P0_IMON1
  CS10  = PVDDCR_CPU1_P0_IMON2
  CS9  = PVDDCR_CPU1_P0_IMON3
  CS8  = PVDDCR_CPU1_P0_IMON4
  CS7  = PVDDCR_CPU1_P0_IMON5
  CS6  = PVDDCR_CPU1_P0_IMON6
  CS5  = NC_PVDDCR_CPU1_P0_IMON7
  CS4  = NC_PVDDCR_CPU1_P0_IMON8
  CS3  = PVDDIO_P0_IMON4
  CS2  = PVDDIO_P0_IMON3
  CS1  = PVDDIO_P0_IMON2
  CS0  = PVDDIO_P0_IMON1
  RGND1  = VSENSE_VSS_SENSE_B_P0
  VSEN1  = VSENSE_PVDDIO_P0_VSEN1
  OCP_L  = PVDDCR_CPU1_P0_OCP_N_R
  \en1||addr_cfg\  = PVDDCR_CPU1_P0_EN1_ADDR_CFG
  TEMP1  = PVDDIO_P0_TEMP1
  TEMP0  = PVDDCR_CPU1_P0_TEMP0
  \vmon||iinsen\  = PVDDCR_CPU1_P0_VMON
  VINSEN  = PVDDCR_CPU1_P0_VINSEN
  VCC  = PVDDCR_CPU1_P0_VCC
  VCCS  = PVDDCR_CPU1_P0_VCCS
  TH_GND  = GND

(kicad_pcb
	(version 20260206)
	(generator "pcbnew")
	(generator_version "10.0")
	(general
		(thickness 1.6)
		(legacy_teardrops no)
	)
	(paper "A4")
	(title_block
		(title "04192023_DAF0TMB3IC0_F0TG_MB_C_brd_V02_OCP.brd")
		(comment 1 "Grand Teton / footprint 4890 of 8354 (PU12), pads 1-42 of 49")
	)
	(layers
		(0 "F.Cu" signal "TOP")
		(4 "In1.Cu" signal "GND")
		(6 "In2.Cu" signal "IN1")
		(8 "In3.Cu" signal "GND1")
		(10 "In4.Cu" signal "IN2")
		(12 "In5.Cu" signal "GND2")
		(14 "In6.Cu" signal "IN3")
		(16 "In7.Cu" signal "GND3")
		(18 "In8.Cu" signal "VCC")
		(20 "In9.Cu" signal "VCC1")
		(22 "In10.Cu" signal "GND4")
		(24 "In11.Cu" signal "IN4")
		(26 "In12.Cu" signal "GND5")
		(28 "In13.Cu" signal "IN5")
		(30 "In14.Cu" signal "GND6")
		(32 "In15.Cu" signal "IN6")
		(34 "In16.Cu" signal "GND7")
		(2 "B.Cu" signal "BOTTOM")
		(9 "F.Adhes" user "F.Adhesive")
		(11 "B.Adhes" user "B.Adhesive")
		(13 "F.Paste" user "Package Geometry/Pastemask Top")
		(15 "B.Paste" user "Package Geometry/Pastemask Bottom")
		(5 "F.SilkS" user "Ref Des/Silkscreen Top")
		(7 "B.SilkS" user "Ref Des/Silkscreen Bottom")
		(1 "F.Mask" user "Board Geometry/Soldermask Top")
		(3 "B.Mask" user "Board Geometry/Soldermask Bottom")
		(17 "Dwgs.User" user "User.Drawings")
		(19 "Cmts.User" user "User.Comments")
		(21 "Eco1.User" user "User.Eco1")
		(23 "Eco2.User" user "User.Eco2")
		(25 "Edge.Cuts" user "Board Geometry/Outline")
		(27 "Margin" user)
		(31 "F.CrtYd" user "Package Geometry/Place Bound Top")
		(29 "B.CrtYd" user "Package Geometry/Place Bound Bottom")
		(35 "F.Fab" user "Ref Des/Assembly Top")
		(33 "B.Fab" user "Ref Des/Assembly Bottom")
	)
	(footprint ""
		(layer "F.Cu")
		(at 310.134 -360.68 -90)
		(property "Reference" "PU12"
			(at -6.05409 1.856232 0)
			(unlocked yes)
			(layer "F.SilkS")
			(effects
				(font
					(size 0.7874 0.5842)
					(thickness 0.1524)
				)
			)
		)
		(property "Value" ""
			(at 0 0 270)
			(layer "F.Fab")
			(effects
				(font
					(size 1.27 1.27)
				)
			)
		)
		(duplicate_pad_numbers_are_jumpers no)
		(pad "1" smd rect
			(at -2.875026 -2.199894 180)
			(size 0.1778 0.6604)
			(layers "F.Cu" "F.Mask" "F.Paste")
			(net "PVDDIO_P0_PWM1")
		)
		(pad "2" smd rect
			(at -2.875026 -1.800098 180)
			(size 0.1778 0.6604)
			(layers "F.Cu" "F.Mask" "F.Paste")
			(net "PVDDIO_P0_PWM2")
		)
		(pad "3" smd rect
			(at -2.875026 -1.400048 180)
			(size 0.1778 0.6604)
			(layers "F.Cu" "F.Mask" "F.Paste")
			(net "PVDDIO_P0_PWM3")
		)
		(pad "4" smd rect
			(at -2.875026 -0.999998 180)
			(size 0.1778 0.6604)
			(layers "F.Cu" "F.Mask" "F.Paste")
			(net "PVDDIO_P0_PWM4")
		)
		(pad "5" smd rect
			(at -2.875026 -0.599948 180)
			(size 0.1778 0.6604)
			(layers "F.Cu" "F.Mask" "F.Paste")
			(net "NC_PVDDCR_CPU1_P0_PWM8")
		)
		(pad "6" smd rect
			(at -2.875026 -0.199898 180)
			(size 0.1778 0.6604)
			(layers "F.Cu" "F.Mask" "F.Paste")
			(net "NC_PVDDCR_CPU1_P0_PWM7")
		)
		(pad "7" smd rect
			(at -2.875026 0.199898 180)
			(size 0.1778 0.6604)
			(layers "F.Cu" "F.Mask" "F.Paste")
			(net "PVDDCR_CPU1_P0_PWM6")
		)
		(pad "8" smd rect
			(at -2.875026 0.599948 180)
			(size 0.1778 0.6604)
			(layers "F.Cu" "F.Mask" "F.Paste")
			(net "PVDDCR_CPU1_P0_PWM5")
		)
		(pad "9" smd rect
			(at -2.875026 0.999998 180)
			(size 0.1778 0.6604)
			(layers "F.Cu" "F.Mask" "F.Paste")
			(net "PVDDCR_CPU1_P0_PWM4")
		)
		(pad "10" smd rect
			(at -2.875026 1.400048 180)
			(size 0.1778 0.6604)
			(layers "F.Cu" "F.Mask" "F.Paste")
			(net "PVDDCR_CPU1_P0_PWM3")
		)
		(pad "11" smd rect
			(at -2.875026 1.800098 180)
			(size 0.1778 0.6604)
			(layers "F.Cu" "F.Mask" "F.Paste")
			(net "PVDDCR_CPU1_P0_PWM2")
		)
		(pad "12" smd rect
			(at -2.875026 2.199894 180)
			(size 0.1778 0.6604)
			(layers "F.Cu" "F.Mask" "F.Paste")
			(net "PVDDCR_CPU1_P0_PWM1")
		)
		(pad "13" smd rect
			(at -2.199894 2.875026 270)
			(size 0.1778 0.6604)
			(layers "F.Cu" "F.Mask" "F.Paste")
			(net "SMB_DIO_PVDDCR_CPU1_P0_R")
		)
		(pad "14" smd rect
			(at -1.800098 2.875026 270)
			(size 0.1778 0.6604)
			(layers "F.Cu" "F.Mask" "F.Paste")
			(net "SMB_CLK_PVDDCR_CPU1_P0_R")
		)
		(pad "15" smd rect
			(at -1.400048 2.875026 270)
			(size 0.1778 0.6604)
			(layers "F.Cu" "F.Mask" "F.Paste")
			(net "PVDDCR_CPU1_P0_SMB_ALERT_R")
		)
		(pad "16" smd rect
			(at -0.999998 2.875026 270)
			(size 0.1778 0.6604)
			(layers "F.Cu" "F.Mask" "F.Paste")
			(net "PWRGD_PVDDCR_CPU1_P0_R")
		)
		(pad "17" smd rect
			(at -0.599948 2.875026 270)
			(size 0.1778 0.6604)
			(layers "F.Cu" "F.Mask" "F.Paste")
			(net "PVDDCR_CPU1_P0_EN_R")
		)
		(pad "18" smd rect
			(at -0.199898 2.875026 270)
			(size 0.1778 0.6604)
			(layers "F.Cu" "F.Mask" "F.Paste")
			(net "PVDDCR_CPU1_P0_RESET_N_R")
		)
		(pad "19" smd rect
			(at 0.199898 2.875026 270)
			(size 0.1778 0.6604)
			(layers "F.Cu" "F.Mask" "F.Paste")
			(net "PVDD18_S5_P0")
		)
		(pad "20" smd rect
			(at 0.599948 2.875026 270)
			(size 0.1778 0.6604)
			(layers "F.Cu" "F.Mask" "F.Paste")
			(net "PWRGD_PVDDIO_P0_R")
		)
		(pad "21" smd rect
			(at 0.999998 2.875026 270)
			(size 0.1778 0.6604)
			(layers "F.Cu" "F.Mask" "F.Paste")
			(net "SVID_PVDDCR_CPU1_P0_SVD_R1")
		)
		(pad "22" smd rect
			(at 1.400048 2.875026 270)
			(size 0.1778 0.6604)
			(layers "F.Cu" "F.Mask" "F.Paste")
			(net "SVID_PVDDCR_CPU1_P0_SVC_R1")
		)
		(pad "23" smd rect
			(at 1.800098 2.875026 270)
			(size 0.1778 0.6604)
			(layers "F.Cu" "F.Mask" "F.Paste")
			(net "SVID_PVDDCR_CPU1_P0_SVTO_R")
		)
		(pad "24" smd rect
			(at 2.199894 2.875026 270)
			(size 0.1778 0.6604)
			(layers "F.Cu" "F.Mask" "F.Paste")
			(net "SVID_PVDDCR_CPU1_P0_SVTI_R")
		)
		(pad "25" smd rect
			(at 2.875026 2.199894 180)
			(size 0.1778 0.6604)
			(layers "F.Cu" "F.Mask" "F.Paste")
			(net "VSENSE_PVDDCR_CPU1_P0_VSEN0")
		)
		(pad "26" smd rect
			(at 2.875026 1.800098 180)
			(size 0.1778 0.6604)
			(layers "F.Cu" "F.Mask" "F.Paste")
			(net "VSENSE_VSS_SENSE_C_P0")
		)
		(pad "27" smd rect
			(at 2.875026 1.400048 180)
			(size 0.1778 0.6604)
			(layers "F.Cu" "F.Mask" "F.Paste")
			(net "PVDDCR_CPU1_P0_IMON1")
		)
		(pad "28" smd rect
			(at 2.875026 0.999998 180)
			(size 0.1778 0.6604)
			(layers "F.Cu" "F.Mask" "F.Paste")
			(net "PVDDCR_CPU1_P0_IMON2")
		)
		(pad "29" smd rect
			(at 2.875026 0.599948 180)
			(size 0.1778 0.6604)
			(layers "F.Cu" "F.Mask" "F.Paste")
			(net "PVDDCR_CPU1_P0_IMON3")
		)
		(pad "30" smd rect
			(at 2.875026 0.199898 180)
			(size 0.1778 0.6604)
			(layers "F.Cu" "F.Mask" "F.Paste")
			(net "PVDDCR_CPU1_P0_IMON4")
		)
		(pad "31" smd rect
			(at 2.875026 -0.199898 180)
			(size 0.1778 0.6604)
			(layers "F.Cu" "F.Mask" "F.Paste")
			(net "PVDDCR_CPU1_P0_IMON5")
		)
		(pad "32" smd rect
			(at 2.875026 -0.599948 180)
			(size 0.1778 0.6604)
			(layers "F.Cu" "F.Mask" "F.Paste")
			(net "PVDDCR_CPU1_P0_IMON6")
		)
		(pad "33" smd rect
			(at 2.875026 -0.999998 180)
			(size 0.1778 0.6604)
			(layers "F.Cu" "F.Mask" "F.Paste")
			(net "NC_PVDDCR_CPU1_P0_IMON7")
		)
		(pad "34" smd rect
			(at 2.875026 -1.400048 180)
			(size 0.1778 0.6604)
			(layers "F.Cu" "F.Mask" "F.Paste")
			(net "NC_PVDDCR_CPU1_P0_IMON8")
		)
		(pad "35" smd rect
			(at 2.875026 -1.800098 180)
			(size 0.1778 0.6604)
			(layers "F.Cu" "F.Mask" "F.Paste")
			(net "PVDDIO_P0_IMON4")
		)
		(pad "36" smd rect
			(at 2.875026 -2.199894 180)
			(size 0.1778 0.6604)
			(layers "F.Cu" "F.Mask" "F.Paste")
			(net "PVDDIO_P0_IMON3")
		)
		(pad "37" smd rect
			(at 2.199894 -2.875026 270)
			(size 0.1778 0.6604)
			(layers "F.Cu" "F.Mask" "F.Paste")
			(net "PVDDIO_P0_IMON2")
		)
		(pad "38" smd rect
			(at 1.800098 -2.875026 270)
			(size 0.1778 0.6604)
			(layers "F.Cu" "F.Mask" "F.Paste")
			(net "PVDDIO_P0_IMON1")
		)
		(pad "39" smd rect
			(at 1.400048 -2.875026 270)
			(size 0.1778 0.6604)
			(layers "F.Cu" "F.Mask" "F.Paste")
			(net "VSENSE_VSS_SENSE_B_P0")
		)
		(pad "40" smd rect
			(at 0.999998 -2.875026 270)
			(size 0.1778 0.6604)
			(layers "F.Cu" "F.Mask" "F.Paste")
			(net "VSENSE_PVDDIO_P0_VSEN1")
		)
		(pad "41" smd rect
			(at 0.599948 -2.875026 270)
			(size 0.1778 0.6604)
			(layers "F.Cu" "F.Mask" "F.Paste")
			(net "PVDDCR_CPU1_P0_OCP_N_R")
		)
		(pad "42" smd rect
			(at 0.199898 -2.875026 270)
			(size 0.1778 0.6604)
			(layers "F.Cu" "F.Mask" "F.Paste")
			(net "PVDDCR_CPU1_P0_EN1_ADDR_CFG")
		)
	)
)
